(kicad_pcb
	(version 20241229)
	(generator "pcbnew")
	(generator_version "9.0")
	(general
		(thickness 1.6)
		(legacy_teardrops no)
	)
	(paper "A4")
	(title_block
		(title "OCuLink to PCIe adapter")
		(date "2025-06-18")
		(rev "1.0.0")
		(company "Antmicro Ltd")
		(comment 1 "www.antmicro.com")
		(comment 9 "footprints 155-155 of 159")
	)
	(layers
		(0 "F.Cu" signal)
		(4 "In1.Cu" signal)
		(6 "In2.Cu" signal)
		(2 "B.Cu" signal)
		(9 "F.Adhes" user "F.Adhesive")
		(11 "B.Adhes" user "B.Adhesive")
		(13 "F.Paste" user)
		(15 "B.Paste" user)
		(5 "F.SilkS" user "F.Silkscreen")
		(7 "B.SilkS" user "B.Silkscreen")
		(1 "F.Mask" user)
		(3 "B.Mask" user)
		(17 "Dwgs.User" user "User.Drawings")
		(19 "Cmts.User" user "User.Comments")
		(21 "Eco1.User" user "User.Eco1")
		(23 "Eco2.User" user "User.Eco2")
		(25 "Edge.Cuts" user)
		(27 "Margin" user)
		(31 "F.CrtYd" user "F.Courtyard")
		(29 "B.CrtYd" user "B.Courtyard")
		(35 "F.Fab" user)
		(33 "B.Fab" user)
	)
	(footprint "antmicro-footprints:SIC47XED-T1-GE3"
		(layer "F.Cu")
		(at 143.5 91.749999 -90)
		(property "Reference" "U9"
			(at -4.149999 -2.7 180)
			(layer "F.SilkS")
			(effects
				(font
					(size 0.7 0.7)
					(thickness 0.15)
				)
				(justify right top)
			)
		)
		(property "Value" "SIC477ED-T1-GE3"
			(at 0 4.1 90)
			(layer "F.Fab")
			(effects
				(font
					(size 0.7 0.7)
					(thickness 0.15)
				)
				(justify right top)
			)
		)
		(property "Datasheet" "https://www.vishay.com/docs/77113/sic47x.pdf"
			(at 0 0 90)
			(layer "F.Fab")
			(hide yes)
			(effects
				(font
					(size 1.27 1.27)
					(thickness 0.15)
				)
			)
		)
		(property "Description" "DC/DC Synchronous Regulator, Adjustable, 4.5V to 55VIn, 0.8V to 50.6V/6AOut, 2MHz, PowerPAK MLP55-27"
			(at 0 0 90)
			(layer "F.Fab")
			(hide yes)
			(effects
				(font
					(size 1.27 1.27)
					(thickness 0.15)
				)
			)
		)
		(property "Manufacturer" "Vishay"
			(at 0 0 270)
			(unlocked yes)
			(layer "F.Fab")
			(hide yes)
			(effects
				(font
					(size 1 1)
					(thickness 0.15)
				)
			)
		)
		(property "MPN" "SIC477ED-T1-GE3"
			(at 0 0 270)
			(unlocked yes)
			(layer "F.Fab")
			(hide yes)
			(effects
				(font
					(size 1 1)
					(thickness 0.15)
				)
			)
		)
		(property "Author" "Antmicro"
			(at 0 0 270)
			(unlocked yes)
			(layer "F.Fab")
			(hide yes)
			(effects
				(font
					(size 1 1)
					(thickness 0.15)
				)
			)
		)
		(property "License" "Apache-2.0"
			(at 0 0 270)
			(unlocked yes)
			(layer "F.Fab")
			(hide yes)
			(effects
				(font
					(size 1 1)
					(thickness 0.15)
				)
			)
		)
		(sheetname "/USB-PD/")
		(sheetfile "usb-pd.kicad_sch")
		(attr smd)
		(fp_line
			(start -2.5 2.499)
			(end -2.5 2.148)
			(stroke
				(width 0.15)
				(type solid)
			)
			(layer "F.SilkS")
		)
		(fp_line
			(start -2.101 2.499)
			(end -2.5 2.499)
			(stroke
				(width 0.15)
				(type solid)
			)
			(layer "F.SilkS")
		)
		(fp_line
			(start 2.499 2.499)
			(end 2.1 2.499)
			(stroke
				(width 0.15)
				(type solid)
			)
			(layer "F.SilkS")
		)
		(fp_line
			(start 2.499 2.297)
			(end 2.499 2.499)
			(stroke
				(width 0.15)
				(type solid)
			)
			(layer "F.SilkS")
		)
		(fp_line
			(start -2.5 -2.15)
			(end -2.5 -2.5)
			(stroke
				(width 0.15)
				(type solid)
			)
			(layer "F.SilkS")
		)
		(fp_line
			(start -2.5 -2.5)
			(end -2.15 -2.5)
			(stroke
				(width 0.15)
				(type solid)
			)
			(layer "F.SilkS")
		)
		(fp_line
			(start 2.148 -2.5)
			(end 2.499 -2.5)
			(stroke
				(width 0.15)
				(type solid)
			)
			(layer "F.SilkS")
		)
		(fp_line
			(start 2.499 -2.5)
			(end 2.499 -2.15)
			(stroke
				(width 0.15)
				(type solid)
			)
			(layer "F.SilkS")
		)
		(fp_circle
			(center -2.9 -2.1)
			(end -2.849 -2.1)
			(stroke
				(width 0.15)
				(type solid)
			)
			(fill yes)
			(layer "F.SilkS")
		)
		(fp_poly
			(pts
				(xy -0.803 2.1) (xy -1.601 2.1) (xy -1.601 -0.203) (xy -0.803 -0.203)
			)
			(stroke
				(width 0.1)
				(type solid)
			)
			(fill yes)
			(layer "F.Paste")
		)
		(fp_poly
			(pts
				(xy 1.648 2.048) (xy -0.25 2.048) (xy -0.25 1.398) (xy 1.648 1.398)
			)
			(stroke
				(width 0.1)
				(type solid)
			)
			(fill yes)
			(layer "F.Paste")
		)
		(fp_poly
			(pts
				(xy 1.1 0.597) (xy -0.25 0.597) (xy -0.25 -0.25) (xy 1.1 -0.25)
			)
			(stroke
				(width 0.1)
				(type solid)
			)
			(fill yes)
			(layer "F.Paste")
		)
		(fp_poly
			(pts
				(xy -0.453 -0.75) (xy -1.601 -0.75) (xy -1.601 -1.651) (xy -0.453 -1.651)
			)
			(stroke
				(width 0.1)
				(type solid)
			)
			(fill yes)
			(layer "F.Paste")
		)
		(fp_poly
			(pts
				(xy 1.6 -0.75) (xy 0.45 -0.75) (xy 0.45 -1.651) (xy 1.6 -1.651)
			)
			(stroke
				(width 0.1)
				(type solid)
			)
			(fill yes)
			(layer "F.Paste")
		)
		(fp_line
			(start -1.9 3.2)
			(end 1.65 3.2)
			(stroke
				(width 0.05)
				(type solid)
			)
			(layer "F.CrtYd")
		)
		(fp_line
			(start 1.65 3.2)
			(end 1.65 2.75)
			(stroke
				(width 0.05)
				(type solid)
			)
			(layer "F.CrtYd")
		)
		(fp_line
			(start -2.75 2.75)
			(end -1.9 2.75)
			(stroke
				(width 0.05)
				(type solid)
			)
			(layer "F.CrtYd")
		)
		(fp_line
			(start -1.9 2.75)
			(end -1.9 3.2)
			(stroke
				(width 0.05)
				(type solid)
			)
			(layer "F.CrtYd")
		)
		(fp_line
			(start 1.65 2.75)
			(end 2.75 2.75)
			(stroke
				(width 0.05)
				(type solid)
			)
			(layer "F.CrtYd")
		)
		(fp_line
			(start 2.75 2.75)
			(end 2.75 2.3)
			(stroke
				(width 0.05)
				(type solid)
			)
			(layer "F.CrtYd")
		)
		(fp_line
			(start 2.75 2.3)
			(end 3.2 2.3)
			(stroke
				(width 0.05)
				(type solid)
			)
			(layer "F.CrtYd")
		)
		(fp_line
			(start 3.2 2.3)
			(end 3.2 -2.15)
			(stroke
				(width 0.05)
				(type solid)
			)
			(layer "F.CrtYd")
		)
		(fp_line
			(start -3.2 2.15)
			(end -2.75 2.15)
			(stroke
				(width 0.05)
				(type solid)
			)
			(layer "F.CrtYd")
		)
		(fp_line
			(start -2.75 2.15)
			(end -2.75 2.75)
			(stroke
				(width 0.05)
				(type solid)
			)
			(layer "F.CrtYd")
		)
		(fp_line
			(start -3.2 -2.1)
			(end -3.2 2.15)
			(stroke
				(width 0.05)
				(type solid)
			)
			(layer "F.CrtYd")
		)
		(fp_line
			(start -2.75 -2.1)
			(end -3.2 -2.1)
			(stroke
				(width 0.05)
				(type solid)
			)
			(layer "F.CrtYd")
		)
		(fp_line
			(start 2.75 -2.15)
			(end 2.75 -2.75)
			(stroke
				(width 0.05)
				(type solid)
			)
			(layer "F.CrtYd")
		)
		(fp_line
			(start 3.2 -2.15)
			(end 2.75 -2.15)
			(stroke
				(width 0.05)
				(type solid)
			)
			(layer "F.CrtYd")
		)
		(fp_line
			(start -2.75 -2.75)
			(end -2.75 -2.1)
			(stroke
				(width 0.05)
				(type solid)
			)
			(layer "F.CrtYd")
		)
		(fp_line
			(start -2.15 -2.75)
			(end -2.75 -2.75)
			(stroke
				(width 0.05)
				(type solid)
			)
			(layer "F.CrtYd")
		)
		(fp_line
			(start 2.15 -2.75)
			(end 2.15 -3.2)
			(stroke
				(width 0.05)
				(type solid)
			)
			(layer "F.CrtYd")
		)
		(fp_line
			(start 2.75 -2.75)
			(end 2.15 -2.75)
			(stroke
				(width 0.05)
				(type solid)
			)
			(layer "F.CrtYd")
		)
		(fp_line
			(start -2.15 -3.2)
			(end -2.15 -2.75)
			(stroke
				(width 0.05)
				(type solid)
			)
			(layer "F.CrtYd")
		)
		(fp_line
			(start 2.15 -3.2)
			(end -2.15 -3.2)
			(stroke
				(width 0.05)
				(type solid)
			)
			(layer "F.CrtYd")
		)
		(fp_line
			(start -2.5 -2.302)
			(end -2.302 -2.5)
			(stroke
				(width 0.15)
				(type solid)
			)
			(layer "F.Fab")
		)
		(fp_rect
			(start 2.499 2.499)
			(end -2.5 -2.5)
			(stroke
				(width 0.15)
				(type solid)
			)
			(fill no)
			(layer "F.Fab")
		)
		(fp_text user "${REFERENCE}"
			(at 0 0 90)
			(layer "F.Fab")
			(effects
				(font
					(size 0.7 0.7)
					(thickness 0.15)
				)
				(justify right top)
			)
		)
		(fp_text user "Author: Antmicro"
			(at -4.851 8.338999 90)
			(layer "F.Fab")
			(effects
				(font
					(size 0.7 0.7)
					(thickness 0.15)
				)
				(justify right top)
			)
		)
		(fp_text user "License: Apache-2.0"
			(at -4.851 5.94 90)
			(layer "F.Fab")
			(effects
				(font
					(size 0.7 0.7)
					(thickness 0.15)
				)
				(justify right top)
			)
		)
		(pad "1" smd rect
			(at -2.525 -1.7 270)
			(size 0.95 0.35)
			(layers "F.Cu" "F.Mask" "F.Paste")
			(net 115 "/USB-PD/VCC")
			(pinfunction "V_{CIN}")
			(pintype "input")
		)
		(pad "2" smd rect
			(at -2.525 -1.051 270)
			(size 0.95 0.35)
			(layers "F.Cu" "F.Mask" "F.Paste")
			(net 158 "/USB-PD/12V_PG")
			(pinfunction "P_{GOOD}")
			(pintype "output")
		)
		(pad "3" smd rect
			(at -2.525 -0.403 270)
			(size 0.95 0.35)
			(layers "F.Cu" "F.Mask" "F.Paste")
			(net 156 "/USB-PD/12V_EN")
			(pinfunction "EN")
			(pintype "input")
		)
		(pad "4" smd rect
			(at -2.525 0.247 270)
			(size 0.95 0.35)
			(layers "F.Cu" "F.Mask" "F.Paste")
			(net 122 "/USB-PD/12V_BOOT")
			(pinfunction "BOOT")
			(pintype "input")
		)
		(pad "5" smd rect
			(at -2.525 1.249 270)
			(size 0.95 0.35)
			(layers "F.Cu" "F.Mask" "F.Paste")
			(net 120 "Net-(C27-Pad2)")
			(pinfunction "PHASE")
			(pintype "bidirectional")
		)
		(pad "6" smd rect
			(at -2.525 1.749 270)
			(size 0.95 0.35)
			(layers "F.Cu" "F.Mask" "F.Paste")
			(net 120 "Net-(C27-Pad2)")
			(pinfunction "PHASE")
			(pintype "passive")
		)
		(pad "7" smd rect
			(at -1.52 2.523 270)
			(size 0.35 0.95)
			(layers "F.Cu" "F.Mask" "F.Paste")
			(net 115 "/USB-PD/VCC")
			(pinfunction "V_{IN}")
			(pintype "input")
		)
		(pad "7" smd rect
			(at -1.2 0.997 270)
			(size 1.1 2.7)
			(layers "F.Cu" "F.Mask")
			(net 115 "/USB-PD/VCC")
			(pinfunction "V_{IN}")
			(pintype "input")
		)
		(pad "8" smd rect
			(at -0.87 2.523 270)
			(size 0.35 0.95)
			(layers "F.Cu" "F.Mask" "F.Paste")
			(net 115 "/USB-PD/VCC")
			(pinfunction "V_{IN}")
			(pintype "passive")
		)
		(pad "9" smd rect
			(at 0.26 2.523 270)
			(size 0.35 0.95)
			(layers "F.Cu" "F.Mask" "F.Paste")
			(net 66 "GND")
			(pinfunction "PGND")
			(pintype "power_in")
		)
		(pad "9" smd rect
			(at 0.409 0.997 270)
			(size 1.52 2.7)
			(layers "F.Cu" "F.Mask")
			(net 66 "GND")
			(pinfunction "PGND")
			(pintype "power_in")
		)
		(pad "9" smd rect
			(at 0.699 1.485 270)
			(size 2.1 1.73)
			(layers "F.Cu" "F.Mask")
			(net 66 "GND")
			(pinfunction "PGND")
			(pintype "power_in")
		)
		(pad "10" smd rect
			(at 0.757 2.523 270)
			(size 0.35 0.95)
			(layers "F.Cu" "F.Mask" "F.Paste")
			(net 66 "GND")
			(pinfunction "PGND")
			(pintype "passive")
		)
		(pad "11" smd rect
			(at 1.259 2.523 270)
			(size 0.35 0.95)
			(layers "F.Cu" "F.Mask" "F.Paste")
			(net 66 "GND")
			(pinfunction "PGND")
			(pintype "passive")
		)
		(pad "12" smd rect
			(at 2.523 1.898 270)
			(size 0.95 0.35)
			(layers "F.Cu" "F.Mask" "F.Paste")
			(net 143 "/USB-PD/12V_SW")
			(pinfunction "SW")
			(pintype "bidirectional")
		)
		(pad "13" smd rect
			(at 2.523 1.398 270)
			(size 0.95 0.35)
			(layers "F.Cu" "F.Mask" "F.Paste")
			(net 143 "/USB-PD/12V_SW")
			(pinfunction "SW")
			(pintype "passive")
		)
		(pad "14" smd rect
			(at 2.2 1.398 270)
			(size 0.3 1.35)
			(layers "F.Cu" "F.Mask" "F.Paste")
			(net 143 "/USB-PD/12V_SW")
			(pinfunction "SW")
			(pintype "passive")
		)
		(pad "14" smd rect
			(at 2.523 0.9 270)
			(size 0.95 0.35)
			(layers "F.Cu" "F.Mask" "F.Paste")
			(net 143 "/USB-PD/12V_SW")
			(pinfunction "SW")
			(pintype "passive")
		)
		(pad "15" smd rect
			(at 2.523 0.247 270)
			(size 0.95 0.35)
			(layers "F.Cu" "F.Mask" "F.Paste")
			(net 150 "unconnected-(U9-GL-Pad15)")
			(pinfunction "GL")
			(pintype "input+no_connect")
		)
		(pad "16" smd rect
			(at 2.523 -0.25 270)
			(size 0.95 0.35)
			(layers "F.Cu" "F.Mask" "F.Paste")
			(net 123 "/USB-PD/12V_VDRV")
			(pinfunction "V_{DRV}")
			(pintype "passive")
		)
		(pad "17" smd rect
			(at 2.523 -0.75 270)
			(size 0.95 0.35)
			(layers "F.Cu" "F.Mask" "F.Paste")
			(net 66 "GND")
			(pinfunction "PGND")
			(pintype "passive")
		)
		(pad "18" smd rect
			(at 2.523 -1.25 270)
			(size 0.95 0.35)
			(layers "F.Cu" "F.Mask" "F.Paste")
			(net 149 "unconnected-(U9-NC-Pad18)")
			(pinfunction "NC")
			(pintype "passive+no_connect")
		)
		(pad "19" smd rect
			(at 2.523 -1.75 270)
			(size 0.95 0.35)
			(layers "F.Cu" "F.Mask" "F.Paste")
			(net 125 "/USB-PD/12V_SS")
			(pinfunction "SS")
			(pintype "passive")
		)
		(pad "20" smd rect
			(at 1.749 -2.525 270)
			(size 0.35 0.95)
			(layers "F.Cu" "F.Mask" "F.Paste")
			(net 187 "/USB-PD/12V_CONV")
			(pinfunction "V_{SNS}")
			(pintype "power_in")
		)
		(pad "21" smd rect
			(at 1.249 -2.525 270)
			(size 0.35 0.95)
			(layers "F.Cu" "F.Mask" "F.Paste")
			(net 160 "unconnected-(U9-NC-Pad21)")
			(pinfunction "NC")
			(pintype "passive+no_connect")
		)
		(pad "22" smd rect
			(at 0.747 -2.525 270)
			(size 0.35 0.95)
			(layers "F.Cu" "F.Mask" "F.Paste")
			(net 159 "/USB-PD/12V_FB")
			(pinfunction "V_{FB}")
			(pintype "input")
		)
		(pad "23" smd rect
			(at 0.247 -2.525 270)
			(size 0.35 0.95)
			(layers "F.Cu" "F.Mask" "F.Paste")
			(net 66 "GND")
			(pinfunction "AGND")
			(pintype "power_in")
		)
		(pad "24" smd rect
			(at -0.25 -2.525 270)
			(size 0.35 0.95)
			(layers "F.Cu" "F.Mask" "F.Paste")
			(net 157 "/USB-PD/12V_FSW")
			(pinfunction "f_{SW}")
			(pintype "passive")
		)
		(pad "25" smd rect
			(at -0.75 -2.525 270)
			(size 0.35 0.95)
			(layers "F.Cu" "F.Mask" "F.Paste")
			(net 155 "/USB-PD/12V_ILIM")
			(pinfunction "I_{LIMIT}")
			(pintype "passive")
		)
		(pad "26" smd rect
			(at -1.25 -2.525 270)
			(size 0.35 0.95)
			(layers "F.Cu" "F.Mask" "F.Paste")
			(net 121 "/USB-PD/12V_VDD")
			(pinfunction "V_{DD}")
			(pintype "power_out")
		)
		(pad "27" smd rect
			(at -1.75 -2.525 270)
			(size 0.35 0.95)
			(layers "F.Cu" "F.Mask" "F.Paste")
			(net 153 "/USB-PD/12V_MODE")
			(pinfunction "MODE")
			(pintype "bidirectional")
		)
		(pad "28" smd rect
			(at 0 -1.2 270)
			(size 3.4 1.1)
			(layers "F.Cu" "F.Mask")
			(net 66 "GND")
			(pinfunction "AGND")
			(pintype "passive")
		)
	)
)
